# T6G (Grand Teton) — schematic netlist excerpt (pin names and nets, part order shuffled) for the footprints in the layout excerpt that follows; sources: Cadence DE-HDL packaged netlist, KiCad conversion of 04192023_DAF0TMB3IC0_F0TG_MB_C_brd_V02_OCP.brd

D75  Q_LED  IC  pkg SMLF  page 255 : A = LED_PWRGD_PVDDCR_SOC_P0_R ; C = LED_PWRGD_PVDDCR_SOC_P0_D
R8252  Q_RES  1K 1% CHIP  pkg 0402LF  page 217 : A = PVDD18_S5_P1 ; B = PVDDCR_CPU1_P1_OCP_N_R

(kicad_pcb
	(version 20260206)
	(generator "pcbnew")
	(generator_version "10.0")
	(general
		(thickness 1.6)
		(legacy_teardrops no)
	)
	(paper "A4")
	(title_block
		(title "04192023_DAF0TMB3IC0_F0TG_MB_C_brd_V02_OCP.brd")
		(comment 1 "Grand Teton / footprints 2159-2160 of 8354")
	)
	(layers
		(0 "F.Cu" signal "TOP")
		(4 "In1.Cu" signal "GND")
		(6 "In2.Cu" signal "IN1")
		(8 "In3.Cu" signal "GND1")
		(10 "In4.Cu" signal "IN2")
		(12 "In5.Cu" signal "GND2")
		(14 "In6.Cu" signal "IN3")
		(16 "In7.Cu" signal "GND3")
		(18 "In8.Cu" signal "VCC")
		(20 "In9.Cu" signal "VCC1")
		(22 "In10.Cu" signal "GND4")
		(24 "In11.Cu" signal "IN4")
		(26 "In12.Cu" signal "GND5")
		(28 "In13.Cu" signal "IN5")
		(30 "In14.Cu" signal "GND6")
		(32 "In15.Cu" signal "IN6")
		(34 "In16.Cu" signal "GND7")
		(2 "B.Cu" signal "BOTTOM")
		(9 "F.Adhes" user "F.Adhesive")
		(11 "B.Adhes" user "B.Adhesive")
		(13 "F.Paste" user "Package Geometry/Pastemask Top")
		(15 "B.Paste" user "Package Geometry/Pastemask Bottom")
		(5 "F.SilkS" user "Ref Des/Silkscreen Top")
		(7 "B.SilkS" user "Ref Des/Silkscreen Bottom")
		(1 "F.Mask" user "Board Geometry/Soldermask Top")
		(3 "B.Mask" user "Board Geometry/Soldermask Bottom")
		(17 "Dwgs.User" user "User.Drawings")
		(19 "Cmts.User" user "User.Comments")
		(21 "Eco1.User" user "User.Eco1")
		(23 "Eco2.User" user "User.Eco2")
		(25 "Edge.Cuts" user "Board Geometry/Outline")
		(27 "Margin" user)
		(31 "F.CrtYd" user "Package Geometry/Place Bound Top")
		(29 "B.CrtYd" user "Package Geometry/Place Bound Bottom")
		(35 "F.Fab" user "Ref Des/Assembly Top")
		(33 "B.Fab" user "Ref Des/Assembly Bottom")
	)
	(footprint ""
		(layer "F.Cu")
		(at 37.211 -362.077 180)
		(property "Reference" "R8252"
			(at 0 0 180)
			(layer "F.SilkS")
			(hide yes)
			(effects
				(font
					(size 1.27 1.27)
				)
			)
		)
		(property "Value" ""
			(at 0 0 180)
			(layer "F.Fab")
			(effects
				(font
					(size 1.27 1.27)
				)
			)
		)
		(duplicate_pad_numbers_are_jumpers no)
		(fp_line
			(start 0.7874 0.4064)
			(end -0.7874 0.4064)
			(stroke
				(width 0.1524)
				(type default)
			)
			(layer "F.SilkS")
		)
		(fp_line
			(start 0.7874 -0.4064)
			(end 0.7874 0.4064)
			(stroke
				(width 0.1524)
				(type default)
			)
			(layer "F.SilkS")
		)
		(fp_line
			(start -0.7874 0.4064)
			(end -0.7874 -0.4064)
			(stroke
				(width 0.1524)
				(type default)
			)
			(layer "F.SilkS")
		)
		(fp_line
			(start -0.7874 -0.4064)
			(end 0.7874 -0.4064)
			(stroke
				(width 0.1524)
				(type default)
			)
			(layer "F.SilkS")
		)
		(fp_line
			(start 0.67945 0.3048)
			(end 0.120396 0.3048)
			(stroke
				(width 0.1)
				(type default)
			)
			(layer "F.Fab")
		)
		(fp_line
			(start 0.67945 -0.3048)
			(end 0.67945 0.3048)
			(stroke
				(width 0.1)
				(type default)
			)
			(layer "F.Fab")
		)
		(fp_line
			(start 0.12065 -0.2794)
			(end 0.12065 -0.3048)
			(stroke
				(width 0.1)
				(type default)
			)
			(layer "F.Fab")
		)
		(fp_line
			(start 0.12065 -0.3048)
			(end 0.67945 -0.3048)
			(stroke
				(width 0.1)
				(type default)
			)
			(layer "F.Fab")
		)
		(fp_line
			(start 0.120396 0.3048)
			(end 0.120396 0.2794)
			(stroke
				(width 0.1)
				(type default)
			)
			(layer "F.Fab")
		)
		(fp_line
			(start 0.120396 0.2794)
			(end -0.12065 0.2794)
			(stroke
				(width 0.1)
				(type default)
			)
			(layer "F.Fab")
		)
		(fp_line
			(start -0.12065 0.3048)
			(end -0.67945 0.3048)
			(stroke
				(width 0.1)
				(type default)
			)
			(layer "F.Fab")
		)
		(fp_line
			(start -0.12065 0.2794)
			(end -0.12065 0.3048)
			(stroke
				(width 0.1)
				(type default)
			)
			(layer "F.Fab")
		)
		(fp_line
			(start -0.12065 -0.2794)
			(end 0.12065 -0.2794)
			(stroke
				(width 0.1)
				(type default)
			)
			(layer "F.Fab")
		)
		(fp_line
			(start -0.12065 -0.305054)
			(end -0.12065 -0.2794)
			(stroke
				(width 0.1)
				(type default)
			)
			(layer "F.Fab")
		)
		(fp_line
			(start -0.67945 0.3048)
			(end -0.67945 -0.305054)
			(stroke
				(width 0.1)
				(type default)
			)
			(layer "F.Fab")
		)
		(fp_line
			(start -0.67945 -0.305054)
			(end -0.12065 -0.305054)
			(stroke
				(width 0.1)
				(type default)
			)
			(layer "F.Fab")
		)
		(pad "1" smd circle
			(at -0.40005 0 180)
			(size 0 0)
			(layers "F.Cu" "F.Mask" "F.Paste")
			(net "PVDD18_S5_P1")
		)
		(pad "2" smd circle
			(at 0.40005 0 180)
			(size 0 0)
			(layers "F.Cu" "F.Mask" "F.Paste")
			(net "PVDDCR_CPU1_P1_OCP_N_R")
		)
	)
	(footprint ""
		(layer "F.Cu")
		(at 326.667876 -70.098412 90)
		(property "Reference" "D75"
			(at -3.934714 -0.691642 90)
			(unlocked yes)
			(layer "F.SilkS")
			(effects
				(font
					(size 0.7874 0.5842)
					(thickness 0.1524)
				)
				(justify left)
			)
		)
		(property "Value" ""
			(at 0 0 90)
			(layer "F.Fab")
			(effects
				(font
					(size 1.27 1.27)
				)
			)
		)
		(duplicate_pad_numbers_are_jumpers no)
		(fp_line
			(start 1.16078 -0.4826)
			(end 1.16078 0.4826)
			(stroke
				(width 0.1524)
				(type default)
			)
			(layer "F.SilkS")
		)
		(fp_line
			(start 1.03378 -0.4826)
			(end 1.03378 0.4826)
			(stroke
				(width 0.1524)
				(type default)
			)
			(layer "F.SilkS")
		)
		(fp_line
			(start 0.90678 -0.4826)
			(end 0.90678 0.4826)
			(stroke
				(width 0.1524)
				(type default)
			)
			(layer "F.SilkS")
		)
		(fp_line
			(start -0.64008 -0.4826)
			(end 1.16078 -0.4826)
			(stroke
				(width 0.1524)
				(type default)
			)
			(layer "F.SilkS")
		)
		(fp_line
			(start -0.79248 -0.4826)
			(end 1.03378 -0.4826)
			(stroke
				(width 0.1524)
				(type default)
			)
			(layer "F.SilkS")
		)
		(fp_line
			(start -0.89408 -0.4826)
			(end 0.90678 -0.4826)
			(stroke
				(width 0.1524)
				(type default)
			)
			(layer "F.SilkS")
		)
		(fp_line
			(start 1.16078 0.4826)
			(end -0.64008 0.4826)
			(stroke
				(width 0.1524)
				(type default)
			)
			(layer "F.SilkS")
		)
		(fp_line
			(start 1.03378 0.4826)
			(end -0.79248 0.4826)
			(stroke
				(width 0.1524)
				(type default)
			)
			(layer "F.SilkS")
		)
		(fp_line
			(start 0.90678 0.4826)
			(end -0.90678 0.4826)
			(stroke
				(width 0.1524)
				(type default)
			)
			(layer "F.SilkS")
		)
		(fp_line
			(start -0.90678 0.4826)
			(end -0.90678 -0.4699)
			(stroke
				(width 0.1524)
				(type default)
			)
			(layer "F.SilkS")
		)
		(fp_line
			(start 0.499872 -0.249936)
			(end 0.499872 0.249936)
			(stroke
				(width 0.1)
				(type default)
			)
			(layer "F.Fab")
		)
		(fp_line
			(start -0.499872 -0.249936)
			(end 0.499872 -0.249936)
			(stroke
				(width 0.1)
				(type default)
			)
			(layer "F.Fab")
		)
		(fp_line
			(start 0.499872 0.249936)
			(end -0.499872 0.249936)
			(stroke
				(width 0.1)
				(type default)
			)
			(layer "F.Fab")
		)
		(fp_line
			(start -0.499872 0.249936)
			(end -0.499872 -0.249936)
			(stroke
				(width 0.1)
				(type default)
			)
			(layer "F.Fab")
		)
		(pad "A" smd rect
			(at -0.47498 0 90)
			(size 0.6096 0.7112)
			(layers "F.Cu" "F.Mask" "F.Paste")
			(net "LED_PWRGD_PVDDCR_SOC_P0_R")
		)
		(pad "C" smd rect
			(at 0.47498 0 90)
			(size 0.6096 0.7112)
			(layers "F.Cu" "F.Mask" "F.Paste")
			(net "LED_PWRGD_PVDDCR_SOC_P0_D")
		)
	)
)
